(kicad_pcb
	(version 20260206)
	(generator "pcbnew")
	(generator_version "10.0")
	(general
		(thickness 1.6)
		(legacy_teardrops no)
	)
	(paper "A4")
	(title_block
		(title "Bryce Canyon_R.DPB_16317-1_OCP.brd")
		(comment 1 "Bryce Canyon / footprints 244-250 of 2099")
	)
	(layers
		(0 "F.Cu" signal "TOP")
		(4 "In1.Cu" signal "L2GND")
		(6 "In2.Cu" signal "L3")
		(8 "In3.Cu" signal "L4VCC")
		(10 "In4.Cu" signal "L5VCC")
		(12 "In5.Cu" signal "L6")
		(14 "In6.Cu" signal "L7GND")
		(2 "B.Cu" signal "BOTTOM")
		(9 "F.Adhes" user "F.Adhesive")
		(11 "B.Adhes" user "B.Adhesive")
		(13 "F.Paste" user "Package Geometry/Pastemask Top")
		(15 "B.Paste" user "Package Geometry/Pastemask Bottom")
		(5 "F.SilkS" user "Ref Des/Silkscreen Top")
		(7 "B.SilkS" user "Ref Des/Silkscreen Bottom")
		(1 "F.Mask" user "Board Geometry/Soldermask Top")
		(3 "B.Mask" user "Board Geometry/Soldermask Bottom")
		(17 "Dwgs.User" user "User.Drawings")
		(19 "Cmts.User" user "User.Comments")
		(21 "Eco1.User" user "User.Eco1")
		(23 "Eco2.User" user "User.Eco2")
		(25 "Edge.Cuts" user "Board Geometry/Outline")
		(27 "Margin" user)
		(31 "F.CrtYd" user "Package Geometry/Place Bound Top")
		(29 "B.CrtYd" user "Package Geometry/Place Bound Bottom")
		(35 "F.Fab" user "Ref Des/Assembly Top")
		(33 "B.Fab" user "Ref Des/Assembly Bottom")
	)
	(footprint ""
		(layer "F.Cu")
		(at 67.183 -151.003 90)
		(property "Reference" "R373"
			(at 0 0 90)
			(layer "F.SilkS")
			(hide yes)
			(effects
				(font
					(size 1.27 1.27)
				)
			)
		)
		(property "Value" "220R3F-1-GP"
			(at -0.0254 -2.5146 90)
			(unlocked yes)
			(layer "F.Fab")
			(hide yes)
			(effects
				(font
					(size 1.016 1.016)
					(thickness 0.1524)
				)
			)
		)
		(property "Device Type" "R603H22"
			(at -0.0254 -4.0386 90)
			(unlocked yes)
			(layer "F.Fab")
			(hide yes)
			(effects
				(font
					(size 1.016 1.016)
					(thickness 0.1524)
				)
			)
		)
		(duplicate_pad_numbers_are_jumpers no)
		(fp_line
			(start 0.2032 0)
			(end 0.4826 0)
			(stroke
				(width 0.2032)
				(type default)
			)
			(layer "F.SilkS")
		)
		(fp_line
			(start -0.4826 0)
			(end -0.2032 0)
			(stroke
				(width 0.2032)
				(type default)
			)
			(layer "F.SilkS")
		)
		(fp_rect
			(start -0.5842 1.3335)
			(end 0.5842 -1.3335)
			(stroke
				(width 0)
				(type default)
			)
			(fill no)
			(layer "F.CrtYd")
		)
		(fp_rect
			(start -0.5842 1.3335)
			(end 0.5842 -1.3335)
			(stroke
				(width 0)
				(type default)
			)
			(fill no)
			(layer "F.Fab")
		)
		(pad "1" smd custom
			(at 0 -0.762 90)
			(size 0.2159 0.2159)
			(layers "F.Cu" "F.Mask" "F.Paste")
			(net "HDD_PRSNT_13")
			(options
				(clearance outline)
				(anchor circle)
			)
			(primitives
				(gr_poly
					(pts
						(arc
							(start -0.3302 -0.4318)
							(mid -0.402042 -0.402042)
							(end -0.4318 -0.3302)
						)
						(arc
							(start -0.4318 0.3302)
							(mid -0.402042 0.402042)
							(end -0.3302 0.4318)
						)
						(arc
							(start 0.3302 0.4318)
							(mid 0.402042 0.402042)
							(end 0.4318 0.3302)
						)
						(arc
							(start 0.4318 -0.3302)
							(mid 0.402042 -0.402042)
							(end 0.3302 -0.4318)
						)
					)
					(width 0)
					(fill yes)
				)
			)
		)
		(pad "2" smd custom
			(at 0 0.762 90)
			(size 0.2159 0.2159)
			(layers "F.Cu" "F.Mask" "F.Paste")
			(net "DRIVE_B_13_INS")
			(options
				(clearance outline)
				(anchor circle)
			)
			(primitives
				(gr_poly
					(pts
						(arc
							(start -0.3302 -0.4318)
							(mid -0.402042 -0.402042)
							(end -0.4318 -0.3302)
						)
						(arc
							(start -0.4318 0.3302)
							(mid -0.402042 0.402042)
							(end -0.3302 0.4318)
						)
						(arc
							(start 0.3302 0.4318)
							(mid 0.402042 0.402042)
							(end 0.4318 0.3302)
						)
						(arc
							(start 0.4318 -0.3302)
							(mid 0.402042 -0.402042)
							(end 0.3302 -0.4318)
						)
					)
					(width 0)
					(fill yes)
				)
			)
		)
	)
	(footprint ""
		(layer "F.Cu")
		(at 477.52 -20.701 90)
		(property "Reference" "C492"
			(at 0 0 90)
			(layer "F.SilkS")
			(hide yes)
			(effects
				(font
					(size 1.27 1.27)
				)
			)
		)
		(property "Value" "SCD01U50V2KX-1GP"
			(at 1.1811 -2.7051 90)
			(unlocked yes)
			(layer "F.Fab")
			(hide yes)
			(effects
				(font
					(size 1.016 1.016)
					(thickness 0.1524)
				)
			)
		)
		(property "Device Type" "C402H22"
			(at 1.1811 -4.2291 90)
			(unlocked yes)
			(layer "F.Fab")
			(hide yes)
			(effects
				(font
					(size 1.016 1.016)
					(thickness 0.1524)
				)
			)
		)
		(duplicate_pad_numbers_are_jumpers no)
		(fp_rect
			(start -0.4318 0.9525)
			(end 0.4318 -0.9525)
			(stroke
				(width 0)
				(type default)
			)
			(fill no)
			(layer "F.CrtYd")
		)
		(fp_rect
			(start -0.4318 0.9525)
			(end 0.4318 -0.9525)
			(stroke
				(width 0)
				(type default)
			)
			(fill no)
			(layer "F.Fab")
		)
		(pad "1" smd custom
			(at 0 -0.4445 90)
			(size 0.1524 0.1524)
			(layers "F.Cu" "F.Mask" "F.Paste")
			(net "HDD_PRSNT_35")
			(options
				(clearance outline)
				(anchor circle)
			)
			(primitives
				(gr_poly
					(pts
						(arc
							(start 0.3048 -0.2032)
							(mid 0.275042 -0.275042)
							(end 0.2032 -0.3048)
						)
						(arc
							(start -0.2032 -0.3048)
							(mid -0.275042 -0.275042)
							(end -0.3048 -0.2032)
						)
						(arc
							(start -0.3048 0.2032)
							(mid -0.275042 0.275042)
							(end -0.2032 0.3048)
						)
						(arc
							(start 0.2032 0.3048)
							(mid 0.275042 0.275042)
							(end 0.3048 0.2032)
						)
					)
					(width 0)
					(fill yes)
				)
			)
		)
		(pad "2" smd custom
			(at 0 0.4445 90)
			(size 0.1524 0.1524)
			(layers "F.Cu" "F.Mask" "F.Paste")
			(net "GND")
			(options
				(clearance outline)
				(anchor circle)
			)
			(primitives
				(gr_poly
					(pts
						(arc
							(start 0.3048 -0.2032)
							(mid 0.275042 -0.275042)
							(end 0.2032 -0.3048)
						)
						(arc
							(start -0.2032 -0.3048)
							(mid -0.275042 -0.275042)
							(end -0.3048 -0.2032)
						)
						(arc
							(start -0.3048 0.2032)
							(mid -0.275042 0.275042)
							(end -0.2032 0.3048)
						)
						(arc
							(start 0.2032 0.3048)
							(mid 0.275042 0.275042)
							(end 0.3048 0.2032)
						)
					)
					(width 0)
					(fill yes)
				)
			)
		)
	)
	(footprint ""
		(layer "F.Cu")
		(at 259.6515 -380.190756 90)
		(property "Reference" "R1064"
			(at 0 0 90)
			(layer "F.SilkS")
			(hide yes)
			(effects
				(font
					(size 1.27 1.27)
				)
			)
		)
		(property "Value" "100KR2F-L1-GP"
			(at 0.064008 -3.993896 90)
			(unlocked yes)
			(layer "F.Fab")
			(hide yes)
			(effects
				(font
					(size 1.016 1.016)
					(thickness 0.1524)
				)
			)
		)
		(property "Device Type" "R402H16"
			(at 0.064008 -5.517896 90)
			(unlocked yes)
			(layer "F.Fab")
			(hide yes)
			(effects
				(font
					(size 1.016 1.016)
					(thickness 0.1524)
				)
			)
		)
		(duplicate_pad_numbers_are_jumpers no)
		(fp_line
			(start 0.508 -0.9398)
			(end -0.508 -0.9398)
			(stroke
				(width 0.1524)
				(type default)
			)
			(layer "F.SilkS")
		)
		(fp_line
			(start -0.508 -0.9398)
			(end -0.508 0.9398)
			(stroke
				(width 0.1524)
				(type default)
			)
			(layer "F.SilkS")
		)
		(fp_rect
			(start -0.508 0.9398)
			(end 0.508 -0.9398)
			(stroke
				(width 0)
				(type default)
			)
			(fill no)
			(layer "F.CrtYd")
		)
		(fp_rect
			(start -0.508 0.9398)
			(end 0.508 -0.9398)
			(stroke
				(width 0)
				(type default)
			)
			(fill no)
			(layer "F.Fab")
		)
		(pad "1" smd custom
			(at 0 -0.4445 90)
			(size 0.1397 0.1397)
			(layers "F.Cu" "F.Mask" "F.Paste")
			(net "P3V3_IN")
			(options
				(clearance outline)
				(anchor circle)
			)
			(primitives
				(gr_poly
					(pts
						(arc
							(start -0.1778 -0.2794)
							(mid -0.249642 -0.249642)
							(end -0.2794 -0.1778)
						)
						(arc
							(start -0.2794 0.1778)
							(mid -0.249642 0.249642)
							(end -0.1778 0.2794)
						)
						(arc
							(start 0.1778 0.2794)
							(mid 0.249642 0.249642)
							(end 0.2794 0.1778)
						)
						(arc
							(start 0.2794 -0.1778)
							(mid 0.249642 -0.249642)
							(end 0.1778 -0.2794)
						)
					)
					(width 0)
					(fill yes)
				)
			)
		)
		(pad "2" smd custom
			(at 0 0.4445 90)
			(size 0.1397 0.1397)
			(layers "F.Cu" "F.Mask" "F.Paste")
			(net "DRAWER_OUT#_C")
			(options
				(clearance outline)
				(anchor circle)
			)
			(primitives
				(gr_poly
					(pts
						(arc
							(start -0.1778 -0.2794)
							(mid -0.249642 -0.249642)
							(end -0.2794 -0.1778)
						)
						(arc
							(start -0.2794 0.1778)
							(mid -0.249642 0.249642)
							(end -0.1778 0.2794)
						)
						(arc
							(start 0.1778 0.2794)
							(mid 0.249642 0.249642)
							(end 0.2794 0.1778)
						)
						(arc
							(start 0.2794 -0.1778)
							(mid 0.249642 -0.249642)
							(end 0.1778 -0.2794)
						)
					)
					(width 0)
					(fill yes)
				)
			)
		)
	)
	(footprint ""
		(layer "F.Cu")
		(at 273.5834 -332.61173 90)
		(property "Reference" "R89"
			(at 0 0 90)
			(layer "F.SilkS")
			(hide yes)
			(effects
				(font
					(size 1.27 1.27)
				)
			)
		)
		(property "Value" "4K7R2F-GP"
			(at 0.064008 -3.993896 90)
			(unlocked yes)
			(layer "F.Fab")
			(hide yes)
			(effects
				(font
					(size 1.016 1.016)
					(thickness 0.1524)
				)
			)
		)
		(property "Device Type" "R402H16"
			(at 0.064008 -5.517896 90)
			(unlocked yes)
			(layer "F.Fab")
			(hide yes)
			(effects
				(font
					(size 1.016 1.016)
					(thickness 0.1524)
				)
			)
		)
		(duplicate_pad_numbers_are_jumpers no)
		(fp_line
			(start 0.508 -0.9398)
			(end -0.508 -0.9398)
			(stroke
				(width 0.1524)
				(type default)
			)
			(layer "F.SilkS")
		)
		(fp_line
			(start -0.508 -0.9398)
			(end -0.508 0.9398)
			(stroke
				(width 0.1524)
				(type default)
			)
			(layer "F.SilkS")
		)
		(fp_rect
			(start -0.508 0.9398)
			(end 0.508 -0.9398)
			(stroke
				(width 0)
				(type default)
			)
			(fill no)
			(layer "F.CrtYd")
		)
		(fp_rect
			(start -0.508 0.9398)
			(end 0.508 -0.9398)
			(stroke
				(width 0)
				(type default)
			)
			(fill no)
			(layer "F.Fab")
		)
		(pad "1" smd custom
			(at 0 -0.4445 90)
			(size 0.1397 0.1397)
			(layers "F.Cu" "F.Mask" "F.Paste")
			(net "P3V3_IN")
			(options
				(clearance outline)
				(anchor circle)
			)
			(primitives
				(gr_poly
					(pts
						(arc
							(start -0.1778 -0.2794)
							(mid -0.249642 -0.249642)
							(end -0.2794 -0.1778)
						)
						(arc
							(start -0.2794 0.1778)
							(mid -0.249642 0.249642)
							(end -0.1778 0.2794)
						)
						(arc
							(start 0.1778 0.2794)
							(mid 0.249642 0.249642)
							(end 0.2794 0.1778)
						)
						(arc
							(start 0.2794 -0.1778)
							(mid 0.249642 -0.249642)
							(end 0.1778 -0.2794)
						)
					)
					(width 0)
					(fill yes)
				)
			)
		)
		(pad "2" smd custom
			(at 0 0.4445 90)
			(size 0.1397 0.1397)
			(layers "F.Cu" "F.Mask" "F.Paste")
			(net "PWM_OUT_C")
			(options
				(clearance outline)
				(anchor circle)
			)
			(primitives
				(gr_poly
					(pts
						(arc
							(start -0.1778 -0.2794)
							(mid -0.249642 -0.249642)
							(end -0.2794 -0.1778)
						)
						(arc
							(start -0.2794 0.1778)
							(mid -0.249642 0.249642)
							(end -0.1778 0.2794)
						)
						(arc
							(start 0.1778 0.2794)
							(mid 0.249642 0.249642)
							(end 0.2794 0.1778)
						)
						(arc
							(start 0.2794 -0.1778)
							(mid 0.249642 -0.249642)
							(end 0.1778 -0.2794)
						)
					)
					(width 0)
					(fill yes)
				)
			)
		)
	)
	(footprint ""
		(layer "F.Cu")
		(at 472.899994 -180.399944)
		(property "Reference" "LED12"
			(at 0 0 0)
			(layer "F.SilkS")
			(hide yes)
			(effects
				(font
					(size 1.27 1.27)
				)
			)
		)
		(property "Value" "LED-BY-19-GP"
			(at -2.132076 1.414018 0)
			(unlocked yes)
			(layer "F.Fab")
			(hide yes)
			(effects
				(font
					(size 1.016 1.016)
					(thickness 0.1524)
				)
			)
		)
		(property "Device Type" "LED-1615-4PH26"
			(at -2.132076 -0.109982 0)
			(unlocked yes)
			(layer "F.Fab")
			(hide yes)
			(effects
				(font
					(size 1.016 1.016)
					(thickness 0.1524)
				)
			)
		)
		(duplicate_pad_numbers_are_jumpers no)
		(fp_line
			(start -1.2954 0.254)
			(end -1.2954 1.6002)
			(stroke
				(width 0.508)
				(type default)
			)
			(layer "F.SilkS")
		)
		(fp_line
			(start -1.2954 1.6002)
			(end 1.2954 1.6002)
			(stroke
				(width 0.508)
				(type default)
			)
			(layer "F.SilkS")
		)
		(fp_line
			(start -1.1176 -1.4224)
			(end 1.1176 -1.4224)
			(stroke
				(width 0.1524)
				(type default)
			)
			(layer "F.SilkS")
		)
		(fp_line
			(start -1.1176 1.4224)
			(end -1.1176 -1.4224)
			(stroke
				(width 0.1524)
				(type default)
			)
			(layer "F.SilkS")
		)
		(fp_line
			(start 1.1176 -1.4224)
			(end 1.1176 1.4224)
			(stroke
				(width 0.1524)
				(type default)
			)
			(layer "F.SilkS")
		)
		(fp_line
			(start 1.1176 1.4224)
			(end -1.1176 1.4224)
			(stroke
				(width 0.1524)
				(type default)
			)
			(layer "F.SilkS")
		)
		(fp_line
			(start 1.2954 1.6002)
			(end 1.2954 0.254)
			(stroke
				(width 0.508)
				(type default)
			)
			(layer "F.SilkS")
		)
		(fp_rect
			(start -0.7493 0.8001)
			(end 0.7493 -0.8001)
			(stroke
				(width 0)
				(type default)
			)
			(fill no)
			(layer "F.CrtYd")
		)
		(fp_poly
			(pts
				(xy -1.3716 1.6764) (xy -1.3716 -1.6764) (xy 1.3716 -1.6764) (xy 1.3716 0.0635) (xy 0.7493 0.0635)
				(xy 0.7493 -0.8001) (xy -0.7493 -0.8001) (xy -0.7493 0.8001) (xy 0.7493 0.8001) (xy 0.7493 0.0762)
				(xy 1.3716 0.0762) (xy 1.3716 1.6764)
			)
			(stroke
				(width 0)
				(type default)
			)
			(fill no)
			(layer "F.CrtYd")
		)
		(fp_rect
			(start -1.3716 1.6764)
			(end 1.3716 -1.6764)
			(stroke
				(width 0)
				(type default)
			)
			(fill no)
			(layer "F.Fab")
		)
		(pad "1" smd rect
			(at 0.50038 -0.73025)
			(size 0.7112 0.8636)
			(layers "F.Cu" "F.Mask" "F.Paste")
			(net "DRV_ACT_11")
		)
		(pad "2" smd rect
			(at -0.50038 -0.73025)
			(size 0.7112 0.8636)
			(layers "F.Cu" "F.Mask" "F.Paste")
			(net "FLT_HDD11")
		)
		(pad "3" smd rect
			(at 0.50038 0.73025)
			(size 0.7112 0.8636)
			(layers "F.Cu" "F.Mask" "F.Paste")
			(net "DRV_ACT_11_N")
		)
		(pad "4" smd rect
			(at -0.50038 0.73025)
			(size 0.7112 0.8636)
			(layers "F.Cu" "F.Mask" "F.Paste")
			(net "FLT_HDD11_N")
		)
	)
	(footprint ""
		(layer "F.Cu")
		(at 109.65815 -217.337386 -90)
		(property "Reference" "R194"
			(at 0 0 270)
			(layer "F.SilkS")
			(hide yes)
			(effects
				(font
					(size 1.27 1.27)
				)
			)
		)
		(property "Value" "4K7R2F-GP"
			(at 0.064008 -3.993896 270)
			(unlocked yes)
			(layer "F.Fab")
			(hide yes)
			(effects
				(font
					(size 1.016 1.016)
					(thickness 0.1524)
				)
			)
		)
		(property "Device Type" "R402H16"
			(at 0.064008 -5.517896 270)
			(unlocked yes)
			(layer "F.Fab")
			(hide yes)
			(effects
				(font
					(size 1.016 1.016)
					(thickness 0.1524)
				)
			)
		)
		(duplicate_pad_numbers_are_jumpers no)
		(fp_line
			(start -0.508 -0.9398)
			(end -0.508 0.9398)
			(stroke
				(width 0.1524)
				(type default)
			)
			(layer "F.SilkS")
		)
		(fp_line
			(start 0.508 -0.9398)
			(end -0.508 -0.9398)
			(stroke
				(width 0.1524)
				(type default)
			)
			(layer "F.SilkS")
		)
		(fp_rect
			(start -0.508 0.9398)
			(end 0.508 -0.9398)
			(stroke
				(width 0)
				(type default)
			)
			(fill no)
			(layer "F.CrtYd")
		)
		(fp_rect
			(start -0.508 0.9398)
			(end 0.508 -0.9398)
			(stroke
				(width 0)
				(type default)
			)
			(fill no)
			(layer "F.Fab")
		)
		(pad "1" smd custom
			(at 0 -0.4445 270)
			(size 0.1397 0.1397)
			(layers "F.Cu" "F.Mask" "F.Paste")
			(net "DRIVE_B_3_FLT_LED")
			(options
				(clearance outline)
				(anchor circle)
			)
			(primitives
				(gr_poly
					(pts
						(arc
							(start -0.1778 -0.2794)
							(mid -0.249642 -0.249642)
							(end -0.2794 -0.1778)
						)
						(arc
							(start -0.2794 0.1778)
							(mid -0.249642 0.249642)
							(end -0.1778 0.2794)
						)
						(arc
							(start 0.1778 0.2794)
							(mid 0.249642 0.249642)
							(end 0.2794 0.1778)
						)
						(arc
							(start 0.2794 -0.1778)
							(mid 0.249642 -0.249642)
							(end 0.1778 -0.2794)
						)
					)
					(width 0)
					(fill yes)
				)
			)
		)
		(pad "2" smd custom
			(at 0 0.4445 270)
			(size 0.1397 0.1397)
			(layers "F.Cu" "F.Mask" "F.Paste")
			(net "GND")
			(options
				(clearance outline)
				(anchor circle)
			)
			(primitives
				(gr_poly
					(pts
						(arc
							(start -0.1778 -0.2794)
							(mid -0.249642 -0.249642)
							(end -0.2794 -0.1778)
						)
						(arc
							(start -0.2794 0.1778)
							(mid -0.249642 0.249642)
							(end -0.1778 0.2794)
						)
						(arc
							(start 0.1778 0.2794)
							(mid 0.249642 0.249642)
							(end 0.2794 0.1778)
						)
						(arc
							(start 0.2794 -0.1778)
							(mid 0.249642 -0.249642)
							(end 0.1778 -0.2794)
						)
					)
					(width 0)
					(fill yes)
				)
			)
		)
	)
	(footprint ""
		(layer "F.Cu")
		(at 469.9 -139.446 -90)
		(property "Reference" "R614"
			(at 0 0 270)
			(layer "F.SilkS")
			(hide yes)
			(effects
				(font
					(size 1.27 1.27)
				)
			)
		)
		(property "Value" "300KR2F-GP"
			(at 0.064008 -3.993896 270)
			(unlocked yes)
			(layer "F.Fab")
			(hide yes)
			(effects
				(font
					(size 1.016 1.016)
					(thickness 0.1524)
				)
			)
		)
		(property "Device Type" "R402H16"
			(at 0.064008 -5.517896 270)
			(unlocked yes)
			(layer "F.Fab")
			(hide yes)
			(effects
				(font
					(size 1.016 1.016)
					(thickness 0.1524)
				)
			)
		)
		(duplicate_pad_numbers_are_jumpers no)
		(fp_line
			(start -0.508 -0.9398)
			(end -0.508 0.9398)
			(stroke
				(width 0.1524)
				(type default)
			)
			(layer "F.SilkS")
		)
		(fp_line
			(start 0.508 -0.9398)
			(end -0.508 -0.9398)
			(stroke
				(width 0.1524)
				(type default)
			)
			(layer "F.SilkS")
		)
		(fp_rect
			(start -0.508 0.9398)
			(end 0.508 -0.9398)
			(stroke
				(width 0)
				(type default)
			)
			(fill no)
			(layer "F.CrtYd")
		)
		(fp_rect
			(start -0.508 0.9398)
			(end 0.508 -0.9398)
			(stroke
				(width 0)
				(type default)
			)
			(fill no)
			(layer "F.Fab")
		)
		(pad "1" smd custom
			(at 0 -0.4445 270)
			(size 0.1397 0.1397)
			(layers "F.Cu" "F.Mask" "F.Paste")
			(net "SW_HDD_N23")
			(options
				(clearance outline)
				(anchor circle)
			)
			(primitives
				(gr_poly
					(pts
						(arc
							(start -0.1778 -0.2794)
							(mid -0.249642 -0.249642)
							(end -0.2794 -0.1778)
						)
						(arc
							(start -0.2794 0.1778)
							(mid -0.249642 0.249642)
							(end -0.1778 0.2794)
						)
						(arc
							(start 0.1778 0.2794)
							(mid 0.249642 0.249642)
							(end 0.2794 0.1778)
						)
						(arc
							(start 0.2794 -0.1778)
							(mid 0.249642 -0.249642)
							(end 0.1778 -0.2794)
						)
					)
					(width 0)
					(fill yes)
				)
			)
		)
		(pad "2" smd custom
			(at 0 0.4445 270)
			(size 0.1397 0.1397)
			(layers "F.Cu" "F.Mask" "F.Paste")
			(net "P12V_B")
			(options
				(clearance outline)
				(anchor circle)
			)
			(primitives
				(gr_poly
					(pts
						(arc
							(start -0.1778 -0.2794)
							(mid -0.249642 -0.249642)
							(end -0.2794 -0.1778)
						)
						(arc
							(start -0.2794 0.1778)
							(mid -0.249642 0.249642)
							(end -0.1778 0.2794)
						)
						(arc
							(start 0.1778 0.2794)
							(mid 0.249642 0.249642)
							(end 0.2794 0.1778)
						)
						(arc
							(start 0.2794 -0.1778)
							(mid 0.249642 -0.249642)
							(end 0.1778 -0.2794)
						)
					)
					(width 0)
					(fill yes)
				)
			)
		)
	)
)
